# S9S_MB_2U (Grand Teton) — schematic netlist excerpt (pin names and nets, part order shuffled) for the footprints in the layout excerpt that follows; sources: Cadence DE-HDL packaged netlist, KiCad conversion of 03242023_DA0F0TMBIJ0_F0T_Motherboard_J_brd_V01_OCP.brd

R713  Q_RES  10K 1% EMPTY  pkg 0402LF  page 243 : A = P3V3_AUX ; B = MB_FRU_ADDR2
C952  Q_CAP_DIFFBUS  DIFF BUS_0.22UF 6.3V 20% X6S  pkg C0201  page 173 : \1\ = P5E_CPU0_PE2_TX_C_DN<6> ; \2\ = P5E_CPU0_PE2_TX_DN<6>

U259  SN74LVC2G07DCKR  IC  pkg SMLF  page 190
  \1a\  = M2_SSD0_CLKREQ_EN_N
  GND  = GND
  \2a\  = RST_PCIE_PCH_DEV_PERST_M2_R_N
  \2y\  = RST_PCIE_PCH_DEV_BUF_M2_0_PERST
  VCC  = P3V3_AUX
  \1y\  = HDD_ACTIVITY_BUF

(kicad_pcb
	(version 20260206)
	(generator "pcbnew")
	(generator_version "10.0")
	(general
		(thickness 1.6)
		(legacy_teardrops no)
	)
	(paper "A4")
	(title_block
		(title "03242023_DA0F0TMBIJ0_F0T_Motherboard_J_brd_V01_OCP.brd")
		(comment 1 "Grand Teton / footprints 48-50 of 6105")
	)
	(layers
		(0 "F.Cu" signal "TOP")
		(4 "In1.Cu" signal "GND")
		(6 "In2.Cu" signal "IN1")
		(8 "In3.Cu" signal "GND1")
		(10 "In4.Cu" signal "IN2")
		(12 "In5.Cu" signal "GND2")
		(14 "In6.Cu" signal "IN3")
		(16 "In7.Cu" signal "GND3")
		(18 "In8.Cu" signal "VCC")
		(20 "In9.Cu" signal "VCC1")
		(22 "In10.Cu" signal "GND4")
		(24 "In11.Cu" signal "IN4")
		(26 "In12.Cu" signal "GND5")
		(28 "In13.Cu" signal "IN5")
		(30 "In14.Cu" signal "GND6")
		(32 "In15.Cu" signal "IN6")
		(34 "In16.Cu" signal "GND7")
		(2 "B.Cu" signal "BOTTOM")
		(9 "F.Adhes" user "F.Adhesive")
		(11 "B.Adhes" user "B.Adhesive")
		(13 "F.Paste" user "Package Geometry/Pastemask Top")
		(15 "B.Paste" user "Package Geometry/Pastemask Bottom")
		(5 "F.SilkS" user "Ref Des/Silkscreen Top")
		(7 "B.SilkS" user "Ref Des/Silkscreen Bottom")
		(1 "F.Mask" user "Board Geometry/Soldermask Top")
		(3 "B.Mask" user "Board Geometry/Soldermask Bottom")
		(17 "Dwgs.User" user "User.Drawings")
		(19 "Cmts.User" user "User.Comments")
		(21 "Eco1.User" user "User.Eco1")
		(23 "Eco2.User" user "User.Eco2")
		(25 "Edge.Cuts" user "Board Geometry/Outline")
		(27 "Margin" user)
		(31 "F.CrtYd" user "Package Geometry/Place Bound Top")
		(29 "B.CrtYd" user "Package Geometry/Place Bound Bottom")
		(35 "F.Fab" user "Ref Des/Assembly Top")
		(33 "B.Fab" user "Ref Des/Assembly Bottom")
	)
	(footprint ""
		(layer "F.Cu")
		(at 399.88109 -402.371052 -90)
		(property "Reference" "C952"
			(at 0 0 270)
			(layer "F.SilkS")
			(hide yes)
			(effects
				(font
					(size 1.27 1.27)
				)
			)
		)
		(property "Value" ""
			(at 0 0 270)
			(layer "F.Fab")
			(effects
				(font
					(size 1.27 1.27)
				)
			)
		)
		(duplicate_pad_numbers_are_jumpers no)
		(fp_line
			(start -0.299974 0.150114)
			(end -0.299974 -0.150114)
			(stroke
				(width 0.1)
				(type default)
			)
			(layer "F.Fab")
		)
		(fp_line
			(start 0.299974 0.150114)
			(end -0.299974 0.150114)
			(stroke
				(width 0.1)
				(type default)
			)
			(layer "F.Fab")
		)
		(fp_line
			(start -0.299974 -0.150114)
			(end 0.299974 -0.150114)
			(stroke
				(width 0.1)
				(type default)
			)
			(layer "F.Fab")
		)
		(fp_line
			(start 0.299974 -0.150114)
			(end 0.299974 0.150114)
			(stroke
				(width 0.1)
				(type default)
			)
			(layer "F.Fab")
		)
		(pad "1" smd rect
			(at -0.2667 0 270)
			(size 0.3048 0.381)
			(layers "F.Cu" "F.Mask" "F.Paste")
			(net "P5E_CPU0_PE2_TX_C_DN<6>")
		)
		(pad "2" smd rect
			(at 0.2667 0 270)
			(size 0.3048 0.381)
			(layers "F.Cu" "F.Mask" "F.Paste")
			(net "P5E_CPU0_PE2_TX_DN<6>")
		)
	)
	(footprint ""
		(layer "F.Cu")
		(at 135.86841 -41.840404)
		(property "Reference" "U259"
			(at -0.31496 -1.85547 0)
			(unlocked yes)
			(layer "F.SilkS")
			(effects
				(font
					(size 0.7874 0.5842)
					(thickness 0.1524)
				)
			)
		)
		(property "Value" ""
			(at 0 0 0)
			(layer "F.Fab")
			(effects
				(font
					(size 1.27 1.27)
				)
			)
		)
		(duplicate_pad_numbers_are_jumpers no)
		(fp_line
			(start -1.7272 1.1176)
			(end -1.7272 -1.1176)
			(stroke
				(width 0.1524)
				(type default)
			)
			(layer "F.SilkS")
		)
		(fp_line
			(start -0.254 -1.1176)
			(end -1.7272 -1.1176)
			(stroke
				(width 0.1524)
				(type default)
			)
			(layer "F.SilkS")
		)
		(fp_line
			(start 0 -0.7366)
			(end -0.254 -1.1176)
			(stroke
				(width 0.1524)
				(type default)
			)
			(layer "F.SilkS")
		)
		(fp_line
			(start 0.254 -1.1176)
			(end 0 -0.7366)
			(stroke
				(width 0.1524)
				(type default)
			)
			(layer "F.SilkS")
		)
		(fp_line
			(start 1.7272 -1.1176)
			(end 0.254 -1.1176)
			(stroke
				(width 0.1524)
				(type default)
			)
			(layer "F.SilkS")
		)
		(fp_line
			(start 1.7272 -1.1176)
			(end 1.7272 1.1176)
			(stroke
				(width 0.1524)
				(type default)
			)
			(layer "F.SilkS")
		)
		(fp_line
			(start 1.7272 1.1176)
			(end -1.7272 1.1176)
			(stroke
				(width 0.1524)
				(type default)
			)
			(layer "F.SilkS")
		)
		(fp_poly
			(pts
				(xy -2.7178 -0.268986) (xy -2.7178 -1.030986) (xy -1.9558 -0.649986)
			)
			(stroke
				(width 0)
				(type default)
			)
			(fill yes)
			(layer "F.SilkS")
		)
		(fp_line
			(start -1.5748 -1.1176)
			(end -1.5748 1.1176)
			(stroke
				(width 0.1)
				(type default)
			)
			(layer "F.Fab")
		)
		(fp_line
			(start -1.5748 1.1176)
			(end 1.5748 1.1176)
			(stroke
				(width 0.1)
				(type default)
			)
			(layer "F.Fab")
		)
		(fp_line
			(start 1.5748 -1.1176)
			(end -1.5748 -1.1176)
			(stroke
				(width 0.1)
				(type default)
			)
			(layer "F.Fab")
		)
		(fp_line
			(start 1.5748 1.1176)
			(end 1.5748 -1.1176)
			(stroke
				(width 0.1)
				(type default)
			)
			(layer "F.Fab")
		)
		(fp_poly
			(pts
				(xy -1.9558 -0.649986) (xy -2.7178 -0.268986) (xy -2.7178 -1.030986)
			)
			(stroke
				(width 0)
				(type default)
			)
			(fill yes)
			(layer "F.Fab")
		)
		(pad "1" smd rect
			(at -0.999998 -0.649986 270)
			(size 0.3556 1.1176)
			(layers "F.Cu" "F.Mask" "F.Paste")
			(net "M2_SSD0_CLKREQ_EN_N")
		)
		(pad "2" smd rect
			(at -0.999998 0 270)
			(size 0.3556 1.1176)
			(layers "F.Cu" "F.Mask" "F.Paste")
			(net "GND")
		)
		(pad "3" smd rect
			(at -0.999998 0.649986 270)
			(size 0.3556 1.1176)
			(layers "F.Cu" "F.Mask" "F.Paste")
			(net "RST_PCIE_PCH_DEV_PERST_M2_R_N")
		)
		(pad "4" smd rect
			(at 0.999998 0.649986 270)
			(size 0.3556 1.1176)
			(layers "F.Cu" "F.Mask" "F.Paste")
			(net "RST_PCIE_PCH_DEV_BUF_M2_0_PERST")
		)
		(pad "5" smd rect
			(at 0.999998 0 270)
			(size 0.3556 1.1176)
			(layers "F.Cu" "F.Mask" "F.Paste")
			(net "P3V3_AUX")
		)
		(pad "6" smd rect
			(at 0.999998 -0.649986 270)
			(size 0.3556 1.1176)
			(layers "F.Cu" "F.Mask" "F.Paste")
			(net "HDD_ACTIVITY_BUF")
		)
	)
	(footprint ""
		(layer "F.Cu")
		(at 277.61946 -93.741494)
		(property "Reference" "R713"
			(at 0 0 0)
			(layer "F.SilkS")
			(hide yes)
			(effects
				(font
					(size 1.27 1.27)
				)
			)
		)
		(property "Value" ""
			(at 0 0 0)
			(layer "F.Fab")
			(effects
				(font
					(size 1.27 1.27)
				)
			)
		)
		(duplicate_pad_numbers_are_jumpers no)
		(fp_line
			(start -0.7874 -0.4064)
			(end 0.7874 -0.4064)
			(stroke
				(width 0.1524)
				(type default)
			)
			(layer "F.SilkS")
		)
		(fp_line
			(start -0.7874 0.4064)
			(end -0.7874 -0.4064)
			(stroke
				(width 0.1524)
				(type default)
			)
			(layer "F.SilkS")
		)
		(fp_line
			(start 0.7874 -0.4064)
			(end 0.7874 0.4064)
			(stroke
				(width 0.1524)
				(type default)
			)
			(layer "F.SilkS")
		)
		(fp_line
			(start 0.7874 0.4064)
			(end -0.7874 0.4064)
			(stroke
				(width 0.1524)
				(type default)
			)
			(layer "F.SilkS")
		)
		(fp_line
			(start -0.67945 -0.305054)
			(end -0.12065 -0.305054)
			(stroke
				(width 0.1)
				(type default)
			)
			(layer "F.Fab")
		)
		(fp_line
			(start -0.67945 0.3048)
			(end -0.67945 -0.305054)
			(stroke
				(width 0.1)
				(type default)
			)
			(layer "F.Fab")
		)
		(fp_line
			(start -0.12065 -0.305054)
			(end -0.12065 -0.2794)
			(stroke
				(width 0.1)
				(type default)
			)
			(layer "F.Fab")
		)
		(fp_line
			(start -0.12065 -0.2794)
			(end 0.12065 -0.2794)
			(stroke
				(width 0.1)
				(type default)
			)
			(layer "F.Fab")
		)
		(fp_line
			(start -0.12065 0.2794)
			(end -0.12065 0.3048)
			(stroke
				(width 0.1)
				(type default)
			)
			(layer "F.Fab")
		)
		(fp_line
			(start -0.12065 0.3048)
			(end -0.67945 0.3048)
			(stroke
				(width 0.1)
				(type default)
			)
			(layer "F.Fab")
		)
		(fp_line
			(start 0.120396 0.2794)
			(end -0.12065 0.2794)
			(stroke
				(width 0.1)
				(type default)
			)
			(layer "F.Fab")
		)
		(fp_line
			(start 0.120396 0.3048)
			(end 0.120396 0.2794)
			(stroke
				(width 0.1)
				(type default)
			)
			(layer "F.Fab")
		)
		(fp_line
			(start 0.12065 -0.3048)
			(end 0.67945 -0.3048)
			(stroke
				(width 0.1)
				(type default)
			)
			(layer "F.Fab")
		)
		(fp_line
			(start 0.12065 -0.2794)
			(end 0.12065 -0.3048)
			(stroke
				(width 0.1)
				(type default)
			)
			(layer "F.Fab")
		)
		(fp_line
			(start 0.67945 -0.3048)
			(end 0.67945 0.3048)
			(stroke
				(width 0.1)
				(type default)
			)
			(layer "F.Fab")
		)
		(fp_line
			(start 0.67945 0.3048)
			(end 0.120396 0.3048)
			(stroke
				(width 0.1)
				(type default)
			)
			(layer "F.Fab")
		)
		(pad "1" smd circle
			(at -0.40005 0)
			(size 0 0)
			(layers "F.Cu" "F.Mask" "F.Paste")
			(net "P3V3_AUX")
		)
		(pad "2" smd circle
			(at 0.40005 0)
			(size 0 0)
			(layers "F.Cu" "F.Mask" "F.Paste")
			(net "MB_FRU_ADDR2")
		)
	)
)
